# S9S_MB_2U (Grand Teton) — schematic netlist excerpt (pin names and nets, part order shuffled) for the footprints in the layout excerpt that follows; sources: Cadence DE-HDL packaged netlist, KiCad conversion of 03242023_DA0F0TMBIJ0_F0T_Motherboard_J_brd_V01_OCP.brd

R2730  Q_RES  33.2 1% CHIP  pkg 0402LF  page 114 : A = PWRGD_CHC_CPU0_DIMM2 ; B = PWRGD_FAIL_CPU0_CD

(kicad_pcb
	(version 20260206)
	(generator "pcbnew")
	(generator_version "10.0")
	(general
		(thickness 1.6)
		(legacy_teardrops no)
	)
	(paper "A4")
	(title_block
		(title "03242023_DA0F0TMBIJ0_F0T_Motherboard_J_brd_V01_OCP.brd")
		(comment 1 "Grand Teton / footprints 4628-4629 of 6105")
	)
	(layers
		(0 "F.Cu" signal "TOP")
		(4 "In1.Cu" signal "GND")
		(6 "In2.Cu" signal "IN1")
		(8 "In3.Cu" signal "GND1")
		(10 "In4.Cu" signal "IN2")
		(12 "In5.Cu" signal "GND2")
		(14 "In6.Cu" signal "IN3")
		(16 "In7.Cu" signal "GND3")
		(18 "In8.Cu" signal "VCC")
		(20 "In9.Cu" signal "VCC1")
		(22 "In10.Cu" signal "GND4")
		(24 "In11.Cu" signal "IN4")
		(26 "In12.Cu" signal "GND5")
		(28 "In13.Cu" signal "IN5")
		(30 "In14.Cu" signal "GND6")
		(32 "In15.Cu" signal "IN6")
		(34 "In16.Cu" signal "GND7")
		(2 "B.Cu" signal "BOTTOM")
		(9 "F.Adhes" user "F.Adhesive")
		(11 "B.Adhes" user "B.Adhesive")
		(13 "F.Paste" user "Package Geometry/Pastemask Top")
		(15 "B.Paste" user "Package Geometry/Pastemask Bottom")
		(5 "F.SilkS" user "Ref Des/Silkscreen Top")
		(7 "B.SilkS" user "Ref Des/Silkscreen Bottom")
		(1 "F.Mask" user "Board Geometry/Soldermask Top")
		(3 "B.Mask" user "Board Geometry/Soldermask Bottom")
		(17 "Dwgs.User" user "User.Drawings")
		(19 "Cmts.User" user "User.Comments")
		(21 "Eco1.User" user "User.Eco1")
		(23 "Eco2.User" user "User.Eco2")
		(25 "Edge.Cuts" user "Board Geometry/Outline")
		(27 "Margin" user)
		(31 "F.CrtYd" user "Package Geometry/Place Bound Top")
		(29 "B.CrtYd" user "Package Geometry/Place Bound Bottom")
		(35 "F.Fab" user "Ref Des/Assembly Top")
		(33 "B.Fab" user "Ref Des/Assembly Bottom")
	)
	(footprint ""
		(layer "B.Cu")
		(at 479.84537 -179.526692 -90)
		(property "Reference" "X46"
			(at -0.305308 4.89204 270)
			(unlocked yes)
			(layer "B.SilkS")
			(effects
				(font
					(size 0.7874 0.5842)
					(thickness 0.1524)
				)
				(justify left mirror)
			)
		)
		(property "Value" ""
			(at 0 0 90)
			(layer "B.Fab")
			(effects
				(font
					(size 1.27 1.27)
				)
				(justify mirror)
			)
		)
		(property "Device Type" "TP_TDR_4P_FTS_TH-TP_TDR_4P_DIPA"
			(at -1.30175 1.27 180)
			(unlocked yes)
			(layer "B.Fab")
			(hide yes)
			(effects
				(font
					(size 0.635 0.4064)
					(thickness 0.1524)
				)
				(justify mirror)
			)
		)
		(property "User Part Number" "N_A"
			(at -1.30175 1.27 180)
			(unlocked yes)
			(layer "Cmts.User")
			(hide yes)
			(effects
				(font
					(size 0.635 0.4064)
					(thickness 0.1524)
				)
				(justify mirror)
			)
		)
		(duplicate_pad_numbers_are_jumpers no)
		(fp_line
			(start -2.54 3.81)
			(end -2.54 3.6703)
			(stroke
				(width 0.1524)
				(type default)
			)
			(layer "B.SilkS")
		)
		(fp_line
			(start 0 3.81)
			(end -2.54 3.81)
			(stroke
				(width 0.1524)
				(type default)
			)
			(layer "B.SilkS")
		)
		(fp_line
			(start 0 3.175)
			(end 0 3.81)
			(stroke
				(width 0.1524)
				(type default)
			)
			(layer "B.SilkS")
		)
		(fp_line
			(start -2.54 1.4097)
			(end -2.54 1.1303)
			(stroke
				(width 0.1524)
				(type default)
			)
			(layer "B.SilkS")
		)
		(fp_line
			(start 0 0.635)
			(end 0 1.905)
			(stroke
				(width 0.1524)
				(type default)
			)
			(layer "B.SilkS")
		)
		(fp_line
			(start -2.54 -1.1303)
			(end -2.54 -1.27)
			(stroke
				(width 0.1524)
				(type default)
			)
			(layer "B.SilkS")
		)
		(fp_line
			(start -2.54 -1.27)
			(end 0 -1.27)
			(stroke
				(width 0.1524)
				(type default)
			)
			(layer "B.SilkS")
		)
		(fp_line
			(start 0 -1.27)
			(end 0 -0.635)
			(stroke
				(width 0.1524)
				(type default)
			)
			(layer "B.SilkS")
		)
		(fp_poly
			(pts
				(xy 0.761746 0) (xy 2.285746 -0.762) (xy 2.285746 0.762)
			)
			(stroke
				(width 0)
				(type default)
			)
			(fill yes)
			(layer "B.SilkS")
		)
		(fp_line
			(start -2.54 3.81)
			(end -2.54 -1.27)
			(stroke
				(width 0.1)
				(type default)
			)
			(layer "B.Fab")
		)
		(fp_line
			(start 0 3.81)
			(end -2.54 3.81)
			(stroke
				(width 0.1)
				(type default)
			)
			(layer "B.Fab")
		)
		(fp_line
			(start -2.54 -1.27)
			(end 0 -1.27)
			(stroke
				(width 0.1)
				(type default)
			)
			(layer "B.Fab")
		)
		(fp_line
			(start 0 -1.27)
			(end 0 3.81)
			(stroke
				(width 0.1)
				(type default)
			)
			(layer "B.Fab")
		)
		(fp_poly
			(pts
				(xy 0.761746 0) (xy 2.285746 -0.762) (xy 2.285746 0.762)
			)
			(stroke
				(width 0)
				(type default)
			)
			(fill yes)
			(layer "B.Fab")
		)
		(pad "1" thru_hole circle
			(at 0 0 90)
			(size 1.0033 1.0033)
			(drill 0.249936)
			(layers "*.Cu" "*.Mask")
			(remove_unused_layers no)
			(net "TDR_DIFF_85_NECK_IN5_DN")
			(clearance 0.10795)
			(padstack
				(mode front_inner_back)
				(layer "Inner"
					(shape circle)
					(size 0.8001 0.8001)
					(clearance 0.1524)
				)
				(layer "B.Cu"
					(shape circle)
					(size 1.0033 1.0033)
					(thermal_gap 0.10795)
					(clearance 0.10795)
				)
			)
		)
		(pad "2" thru_hole circle
			(at -2.54 0 90)
			(size 1.9939 1.9939)
			(drill 0.249936)
			(layers "*.Cu" "*.Mask")
			(remove_unused_layers no)
			(net "T1_GND")
			(clearance 0.10795)
			(padstack
				(mode front_inner_back)
				(layer "Inner"
					(shape circle)
					(size 0.8001 0.8001)
					(clearance 0.1524)
				)
				(layer "B.Cu"
					(shape circle)
					(size 1.9939 1.9939)
					(thermal_gap 0.10795)
					(clearance 0.10795)
				)
			)
		)
		(pad "3" thru_hole circle
			(at -2.54 2.54 90)
			(size 1.9939 1.9939)
			(drill 0.249936)
			(layers "*.Cu" "*.Mask")
			(remove_unused_layers no)
			(net "T1_GND")
			(clearance 0.10795)
			(padstack
				(mode front_inner_back)
				(layer "Inner"
					(shape circle)
					(size 0.8001 0.8001)
					(clearance 0.1524)
				)
				(layer "B.Cu"
					(shape circle)
					(size 1.9939 1.9939)
					(thermal_gap 0.10795)
					(clearance 0.10795)
				)
			)
		)
		(pad "4" thru_hole circle
			(at 0 2.54 90)
			(size 1.0033 1.0033)
			(drill 0.249936)
			(layers "*.Cu" "*.Mask")
			(remove_unused_layers no)
			(net "TDR_DIFF_85_NECK_IN5_DP")
			(clearance 0.10795)
			(padstack
				(mode front_inner_back)
				(layer "Inner"
					(shape circle)
					(size 0.8001 0.8001)
					(clearance 0.1524)
				)
				(layer "B.Cu"
					(shape circle)
					(size 1.0033 1.0033)
					(thermal_gap 0.10795)
					(clearance 0.10795)
				)
			)
		)
	)
	(footprint ""
		(layer "B.Cu")
		(at 282.423616 -318.94653 90)
		(property "Reference" "R2730"
			(at 0 0 90)
			(layer "B.SilkS")
			(hide yes)
			(effects
				(font
					(size 1.27 1.27)
				)
				(justify mirror)
			)
		)
		(property "Value" ""
			(at 0 0 90)
			(layer "B.Fab")
			(effects
				(font
					(size 1.27 1.27)
				)
				(justify mirror)
			)
		)
		(duplicate_pad_numbers_are_jumpers no)
		(fp_line
			(start 0.7874 -0.4064)
			(end -0.7874 -0.4064)
			(stroke
				(width 0.1524)
				(type default)
			)
			(layer "B.SilkS")
		)
		(fp_line
			(start -0.7874 -0.4064)
			(end -0.7874 0.4064)
			(stroke
				(width 0.1524)
				(type default)
			)
			(layer "B.SilkS")
		)
		(fp_line
			(start 0.7874 0.4064)
			(end 0.7874 -0.4064)
			(stroke
				(width 0.1524)
				(type default)
			)
			(layer "B.SilkS")
		)
		(fp_line
			(start -0.7874 0.4064)
			(end 0.7874 0.4064)
			(stroke
				(width 0.1524)
				(type default)
			)
			(layer "B.SilkS")
		)
		(fp_line
			(start 0.67945 -0.305054)
			(end 0.12065 -0.305054)
			(stroke
				(width 0.1)
				(type default)
			)
			(layer "B.Fab")
		)
		(fp_line
			(start 0.12065 -0.305054)
			(end 0.12065 -0.2794)
			(stroke
				(width 0.1)
				(type default)
			)
			(layer "B.Fab")
		)
		(fp_line
			(start -0.12065 -0.3048)
			(end -0.67945 -0.3048)
			(stroke
				(width 0.1)
				(type default)
			)
			(layer "B.Fab")
		)
		(fp_line
			(start -0.67945 -0.3048)
			(end -0.67945 0.3048)
			(stroke
				(width 0.1)
				(type default)
			)
			(layer "B.Fab")
		)
		(fp_line
			(start 0.12065 -0.2794)
			(end -0.12065 -0.2794)
			(stroke
				(width 0.1)
				(type default)
			)
			(layer "B.Fab")
		)
		(fp_line
			(start -0.12065 -0.2794)
			(end -0.12065 -0.3048)
			(stroke
				(width 0.1)
				(type default)
			)
			(layer "B.Fab")
		)
		(fp_line
			(start 0.12065 0.2794)
			(end 0.12065 0.3048)
			(stroke
				(width 0.1)
				(type default)
			)
			(layer "B.Fab")
		)
		(fp_line
			(start -0.120396 0.2794)
			(end 0.12065 0.2794)
			(stroke
				(width 0.1)
				(type default)
			)
			(layer "B.Fab")
		)
		(fp_line
			(start 0.67945 0.3048)
			(end 0.67945 -0.305054)
			(stroke
				(width 0.1)
				(type default)
			)
			(layer "B.Fab")
		)
		(fp_line
			(start 0.12065 0.3048)
			(end 0.67945 0.3048)
			(stroke
				(width 0.1)
				(type default)
			)
			(layer "B.Fab")
		)
		(fp_line
			(start -0.120396 0.3048)
			(end -0.120396 0.2794)
			(stroke
				(width 0.1)
				(type default)
			)
			(layer "B.Fab")
		)
		(fp_line
			(start -0.67945 0.3048)
			(end -0.120396 0.3048)
			(stroke
				(width 0.1)
				(type default)
			)
			(layer "B.Fab")
		)
		(pad "1" smd circle
			(at 0.40005 0 270)
			(size 0 0)
			(layers "B.Cu" "B.Mask" "B.Paste")
			(net "PWRGD_CHC_CPU0_DIMM2")
		)
		(pad "2" smd circle
			(at -0.40005 0 270)
			(size 0 0)
			(layers "B.Cu" "B.Mask" "B.Paste")
			(net "PWRGD_FAIL_CPU0_CD")
		)
	)
)
